# S9S_MB_2U (Grand Teton) — schematic netlist excerpt (pin names and nets, part order shuffled) for the footprints in the layout excerpt that follows; sources: Cadence DE-HDL packaged netlist, KiCad conversion of 03242023_DA0F0TMBIJ0_F0T_Motherboard_J_brd_V01_OCP.brd

C44  Q_CAP  2.2UF 6.3V 20% X6S  pkg C0402  page 96 : A = P3V3_AUX ; B = GND
PR4227  Q_RES  0 5% EMPTY  pkg 0402LF  page 276 : A = PVCCFA_EHV_CPU0_VDD1 ; B = PVCCFA_EHV_CPU0_NC2

(kicad_pcb
	(version 20260206)
	(generator "pcbnew")
	(generator_version "10.0")
	(general
		(thickness 1.6)
		(legacy_teardrops no)
	)
	(paper "A4")
	(title_block
		(title "03242023_DA0F0TMBIJ0_F0T_Motherboard_J_brd_V01_OCP.brd")
		(comment 1 "Grand Teton / footprints 4801-4802 of 6105")
	)
	(layers
		(0 "F.Cu" signal "TOP")
		(4 "In1.Cu" signal "GND")
		(6 "In2.Cu" signal "IN1")
		(8 "In3.Cu" signal "GND1")
		(10 "In4.Cu" signal "IN2")
		(12 "In5.Cu" signal "GND2")
		(14 "In6.Cu" signal "IN3")
		(16 "In7.Cu" signal "GND3")
		(18 "In8.Cu" signal "VCC")
		(20 "In9.Cu" signal "VCC1")
		(22 "In10.Cu" signal "GND4")
		(24 "In11.Cu" signal "IN4")
		(26 "In12.Cu" signal "GND5")
		(28 "In13.Cu" signal "IN5")
		(30 "In14.Cu" signal "GND6")
		(32 "In15.Cu" signal "IN6")
		(34 "In16.Cu" signal "GND7")
		(2 "B.Cu" signal "BOTTOM")
		(9 "F.Adhes" user "F.Adhesive")
		(11 "B.Adhes" user "B.Adhesive")
		(13 "F.Paste" user "Package Geometry/Pastemask Top")
		(15 "B.Paste" user "Package Geometry/Pastemask Bottom")
		(5 "F.SilkS" user "Ref Des/Silkscreen Top")
		(7 "B.SilkS" user "Ref Des/Silkscreen Bottom")
		(1 "F.Mask" user "Board Geometry/Soldermask Top")
		(3 "B.Mask" user "Board Geometry/Soldermask Bottom")
		(17 "Dwgs.User" user "User.Drawings")
		(19 "Cmts.User" user "User.Comments")
		(21 "Eco1.User" user "User.Eco1")
		(23 "Eco2.User" user "User.Eco2")
		(25 "Edge.Cuts" user "Board Geometry/Outline")
		(27 "Margin" user)
		(31 "F.CrtYd" user "Package Geometry/Place Bound Top")
		(29 "B.CrtYd" user "Package Geometry/Place Bound Bottom")
		(35 "F.Fab" user "Ref Des/Assembly Top")
		(33 "B.Fab" user "Ref Des/Assembly Bottom")
	)
	(footprint ""
		(layer "B.Cu")
		(at 458.42428 -319.132204)
		(property "Reference" "C44"
			(at 0 0 0)
			(layer "B.SilkS")
			(hide yes)
			(effects
				(font
					(size 1.27 1.27)
				)
				(justify mirror)
			)
		)
		(property "Value" ""
			(at 0 0 0)
			(layer "B.Fab")
			(effects
				(font
					(size 1.27 1.27)
				)
				(justify mirror)
			)
		)
		(duplicate_pad_numbers_are_jumpers no)
		(fp_line
			(start -0.7874 -0.4064)
			(end -0.7874 0.4064)
			(stroke
				(width 0.1524)
				(type default)
			)
			(layer "B.SilkS")
		)
		(fp_line
			(start -0.7874 0.4064)
			(end 0.7874 0.4064)
			(stroke
				(width 0.1524)
				(type default)
			)
			(layer "B.SilkS")
		)
		(fp_line
			(start 0.7874 -0.4064)
			(end -0.7874 -0.4064)
			(stroke
				(width 0.1524)
				(type default)
			)
			(layer "B.SilkS")
		)
		(fp_line
			(start 0.7874 0.4064)
			(end 0.7874 -0.4064)
			(stroke
				(width 0.1524)
				(type default)
			)
			(layer "B.SilkS")
		)
		(fp_line
			(start -0.67945 -0.3048)
			(end -0.67945 0.3048)
			(stroke
				(width 0.1)
				(type default)
			)
			(layer "B.Fab")
		)
		(fp_line
			(start -0.67945 0.3048)
			(end -0.120396 0.3048)
			(stroke
				(width 0.1)
				(type default)
			)
			(layer "B.Fab")
		)
		(fp_line
			(start -0.12065 -0.3048)
			(end -0.67945 -0.3048)
			(stroke
				(width 0.1)
				(type default)
			)
			(layer "B.Fab")
		)
		(fp_line
			(start -0.12065 -0.2794)
			(end -0.12065 -0.3048)
			(stroke
				(width 0.1)
				(type default)
			)
			(layer "B.Fab")
		)
		(fp_line
			(start -0.120396 0.2794)
			(end 0.12065 0.2794)
			(stroke
				(width 0.1)
				(type default)
			)
			(layer "B.Fab")
		)
		(fp_line
			(start -0.120396 0.3048)
			(end -0.120396 0.2794)
			(stroke
				(width 0.1)
				(type default)
			)
			(layer "B.Fab")
		)
		(fp_line
			(start 0.12065 -0.305054)
			(end 0.12065 -0.2794)
			(stroke
				(width 0.1)
				(type default)
			)
			(layer "B.Fab")
		)
		(fp_line
			(start 0.12065 -0.2794)
			(end -0.12065 -0.2794)
			(stroke
				(width 0.1)
				(type default)
			)
			(layer "B.Fab")
		)
		(fp_line
			(start 0.12065 0.2794)
			(end 0.12065 0.3048)
			(stroke
				(width 0.1)
				(type default)
			)
			(layer "B.Fab")
		)
		(fp_line
			(start 0.12065 0.3048)
			(end 0.67945 0.3048)
			(stroke
				(width 0.1)
				(type default)
			)
			(layer "B.Fab")
		)
		(fp_line
			(start 0.67945 -0.305054)
			(end 0.12065 -0.305054)
			(stroke
				(width 0.1)
				(type default)
			)
			(layer "B.Fab")
		)
		(fp_line
			(start 0.67945 0.3048)
			(end 0.67945 -0.305054)
			(stroke
				(width 0.1)
				(type default)
			)
			(layer "B.Fab")
		)
		(pad "1" smd circle
			(at 0.40005 0 180)
			(size 0 0)
			(layers "B.Cu" "B.Mask" "B.Paste")
			(net "P3V3_AUX")
		)
		(pad "2" smd circle
			(at -0.40005 0 180)
			(size 0 0)
			(layers "B.Cu" "B.Mask" "B.Paste")
			(net "GND")
		)
	)
	(footprint ""
		(layer "B.Cu")
		(at 422.5163 -154.262328)
		(property "Reference" "PR4227"
			(at 0 0 0)
			(layer "B.SilkS")
			(hide yes)
			(effects
				(font
					(size 1.27 1.27)
				)
				(justify mirror)
			)
		)
		(property "Value" ""
			(at 0 0 0)
			(layer "B.Fab")
			(effects
				(font
					(size 1.27 1.27)
				)
				(justify mirror)
			)
		)
		(duplicate_pad_numbers_are_jumpers no)
		(fp_line
			(start -0.7874 -0.4064)
			(end -0.7874 0.4064)
			(stroke
				(width 0.1524)
				(type default)
			)
			(layer "B.SilkS")
		)
		(fp_line
			(start -0.7874 0.4064)
			(end 0.7874 0.4064)
			(stroke
				(width 0.1524)
				(type default)
			)
			(layer "B.SilkS")
		)
		(fp_line
			(start 0.7874 -0.4064)
			(end -0.7874 -0.4064)
			(stroke
				(width 0.1524)
				(type default)
			)
			(layer "B.SilkS")
		)
		(fp_line
			(start 0.7874 0.4064)
			(end 0.7874 -0.4064)
			(stroke
				(width 0.1524)
				(type default)
			)
			(layer "B.SilkS")
		)
		(fp_line
			(start -0.67945 -0.3048)
			(end -0.67945 0.3048)
			(stroke
				(width 0.1)
				(type default)
			)
			(layer "B.Fab")
		)
		(fp_line
			(start -0.67945 0.3048)
			(end -0.120396 0.3048)
			(stroke
				(width 0.1)
				(type default)
			)
			(layer "B.Fab")
		)
		(fp_line
			(start -0.12065 -0.3048)
			(end -0.67945 -0.3048)
			(stroke
				(width 0.1)
				(type default)
			)
			(layer "B.Fab")
		)
		(fp_line
			(start -0.12065 -0.2794)
			(end -0.12065 -0.3048)
			(stroke
				(width 0.1)
				(type default)
			)
			(layer "B.Fab")
		)
		(fp_line
			(start -0.120396 0.2794)
			(end 0.12065 0.2794)
			(stroke
				(width 0.1)
				(type default)
			)
			(layer "B.Fab")
		)
		(fp_line
			(start -0.120396 0.3048)
			(end -0.120396 0.2794)
			(stroke
				(width 0.1)
				(type default)
			)
			(layer "B.Fab")
		)
		(fp_line
			(start 0.12065 -0.305054)
			(end 0.12065 -0.2794)
			(stroke
				(width 0.1)
				(type default)
			)
			(layer "B.Fab")
		)
		(fp_line
			(start 0.12065 -0.2794)
			(end -0.12065 -0.2794)
			(stroke
				(width 0.1)
				(type default)
			)
			(layer "B.Fab")
		)
		(fp_line
			(start 0.12065 0.2794)
			(end 0.12065 0.3048)
			(stroke
				(width 0.1)
				(type default)
			)
			(layer "B.Fab")
		)
		(fp_line
			(start 0.12065 0.3048)
			(end 0.67945 0.3048)
			(stroke
				(width 0.1)
				(type default)
			)
			(layer "B.Fab")
		)
		(fp_line
			(start 0.67945 -0.305054)
			(end 0.12065 -0.305054)
			(stroke
				(width 0.1)
				(type default)
			)
			(layer "B.Fab")
		)
		(fp_line
			(start 0.67945 0.3048)
			(end 0.67945 -0.305054)
			(stroke
				(width 0.1)
				(type default)
			)
			(layer "B.Fab")
		)
		(pad "1" smd circle
			(at 0.40005 0 180)
			(size 0 0)
			(layers "B.Cu" "B.Mask" "B.Paste")
			(net "PVCCFA_EHV_CPU0_VDD1")
		)
		(pad "2" smd circle
			(at -0.40005 0 180)
			(size 0 0)
			(layers "B.Cu" "B.Mask" "B.Paste")
			(net "PVCCFA_EHV_CPU0_NC2")
		)
	)
)
